(kicad_pcb
	(version 20260206)
	(generator "pcbnew")
	(generator_version "10.0")
	(general
		(thickness 1.6)
		(legacy_teardrops no)
	)
	(paper "A4")
	(title_block
		(title "04192023_DAF0TMB3IC0_F0TG_MB_C_brd_V02_OCP.brd")
		(comment 1 "Grand Teton / footprints 647-653 of 8354")
	)
	(layers
		(0 "F.Cu" signal "TOP")
		(4 "In1.Cu" signal "GND")
		(6 "In2.Cu" signal "IN1")
		(8 "In3.Cu" signal "GND1")
		(10 "In4.Cu" signal "IN2")
		(12 "In5.Cu" signal "GND2")
		(14 "In6.Cu" signal "IN3")
		(16 "In7.Cu" signal "GND3")
		(18 "In8.Cu" signal "VCC")
		(20 "In9.Cu" signal "VCC1")
		(22 "In10.Cu" signal "GND4")
		(24 "In11.Cu" signal "IN4")
		(26 "In12.Cu" signal "GND5")
		(28 "In13.Cu" signal "IN5")
		(30 "In14.Cu" signal "GND6")
		(32 "In15.Cu" signal "IN6")
		(34 "In16.Cu" signal "GND7")
		(2 "B.Cu" signal "BOTTOM")
		(9 "F.Adhes" user "F.Adhesive")
		(11 "B.Adhes" user "B.Adhesive")
		(13 "F.Paste" user "Package Geometry/Pastemask Top")
		(15 "B.Paste" user "Package Geometry/Pastemask Bottom")
		(5 "F.SilkS" user "Ref Des/Silkscreen Top")
		(7 "B.SilkS" user "Ref Des/Silkscreen Bottom")
		(1 "F.Mask" user "Board Geometry/Soldermask Top")
		(3 "B.Mask" user "Board Geometry/Soldermask Bottom")
		(17 "Dwgs.User" user "User.Drawings")
		(19 "Cmts.User" user "User.Comments")
		(21 "Eco1.User" user "User.Eco1")
		(23 "Eco2.User" user "User.Eco2")
		(25 "Edge.Cuts" user "Board Geometry/Outline")
		(27 "Margin" user)
		(31 "F.CrtYd" user "Package Geometry/Place Bound Top")
		(29 "B.CrtYd" user "Package Geometry/Place Bound Bottom")
		(35 "F.Fab" user "Ref Des/Assembly Top")
		(33 "B.Fab" user "Ref Des/Assembly Bottom")
	)
	(footprint ""
		(layer "F.Cu")
		(at 88.23452 -159.029908 -90)
		(property "Reference" "PL30"
			(at -0.049784 -3.804412 90)
			(unlocked yes)
			(layer "F.SilkS")
			(effects
				(font
					(size 0.7874 0.5842)
					(thickness 0.1524)
				)
				(justify left)
			)
		)
		(property "Value" ""
			(at 0 0 270)
			(layer "F.Fab")
			(effects
				(font
					(size 1.27 1.27)
				)
			)
		)
		(duplicate_pad_numbers_are_jumpers no)
		(fp_line
			(start -3.050032 2.999994)
			(end 3.050032 2.999994)
			(stroke
				(width 0.1524)
				(type default)
			)
			(layer "F.SilkS")
		)
		(fp_line
			(start 3.050032 2.999994)
			(end 3.050032 1.4478)
			(stroke
				(width 0.1524)
				(type default)
			)
			(layer "F.SilkS")
		)
		(fp_line
			(start -3.050032 1.4478)
			(end -3.050032 2.999994)
			(stroke
				(width 0.1524)
				(type default)
			)
			(layer "F.SilkS")
		)
		(fp_line
			(start 3.050032 -1.4478)
			(end 3.050032 -2.999994)
			(stroke
				(width 0.1524)
				(type default)
			)
			(layer "F.SilkS")
		)
		(fp_line
			(start -3.050032 -2.999994)
			(end -3.050032 -1.4478)
			(stroke
				(width 0.1524)
				(type default)
			)
			(layer "F.SilkS")
		)
		(fp_line
			(start 3.050032 -2.999994)
			(end -3.050032 -2.999994)
			(stroke
				(width 0.1524)
				(type default)
			)
			(layer "F.SilkS")
		)
		(fp_line
			(start -3.050032 2.999994)
			(end 3.050032 2.999994)
			(stroke
				(width 0.1)
				(type default)
			)
			(layer "F.Fab")
		)
		(fp_line
			(start 3.050032 2.999994)
			(end 3.050032 -2.999994)
			(stroke
				(width 0.1)
				(type default)
			)
			(layer "F.Fab")
		)
		(fp_line
			(start -3.050032 -2.999994)
			(end -3.050032 2.999994)
			(stroke
				(width 0.1)
				(type default)
			)
			(layer "F.Fab")
		)
		(fp_line
			(start 3.050032 -2.999994)
			(end -3.050032 -2.999994)
			(stroke
				(width 0.1)
				(type default)
			)
			(layer "F.Fab")
		)
		(pad "1" smd rect
			(at -2.525014 0 270)
			(size 1.651 2.6162)
			(layers "F.Cu" "F.Mask" "F.Paste")
			(net "SW_P12V_AUX_PVDDCR_CPU0_P1_FLT")
		)
		(pad "2" smd rect
			(at 2.525014 0 270)
			(size 1.651 2.6162)
			(layers "F.Cu" "F.Mask" "F.Paste")
			(net "P12V_AUX")
		)
	)
	(footprint ""
		(layer "F.Cu")
		(at 279.513792 -118.70817 180)
		(property "Reference" "R3394"
			(at 0 0 180)
			(layer "F.SilkS")
			(hide yes)
			(effects
				(font
					(size 1.27 1.27)
				)
			)
		)
		(property "Value" ""
			(at 0 0 180)
			(layer "F.Fab")
			(effects
				(font
					(size 1.27 1.27)
				)
			)
		)
		(duplicate_pad_numbers_are_jumpers no)
		(fp_line
			(start 0.7874 0.4064)
			(end -0.7874 0.4064)
			(stroke
				(width 0.1524)
				(type default)
			)
			(layer "F.SilkS")
		)
		(fp_line
			(start 0.7874 -0.4064)
			(end 0.7874 0.4064)
			(stroke
				(width 0.1524)
				(type default)
			)
			(layer "F.SilkS")
		)
		(fp_line
			(start -0.7874 0.4064)
			(end -0.7874 -0.4064)
			(stroke
				(width 0.1524)
				(type default)
			)
			(layer "F.SilkS")
		)
		(fp_line
			(start -0.7874 -0.4064)
			(end 0.7874 -0.4064)
			(stroke
				(width 0.1524)
				(type default)
			)
			(layer "F.SilkS")
		)
		(fp_line
			(start 0.67945 0.3048)
			(end 0.120396 0.3048)
			(stroke
				(width 0.1)
				(type default)
			)
			(layer "F.Fab")
		)
		(fp_line
			(start 0.67945 -0.3048)
			(end 0.67945 0.3048)
			(stroke
				(width 0.1)
				(type default)
			)
			(layer "F.Fab")
		)
		(fp_line
			(start 0.12065 -0.2794)
			(end 0.12065 -0.3048)
			(stroke
				(width 0.1)
				(type default)
			)
			(layer "F.Fab")
		)
		(fp_line
			(start 0.12065 -0.3048)
			(end 0.67945 -0.3048)
			(stroke
				(width 0.1)
				(type default)
			)
			(layer "F.Fab")
		)
		(fp_line
			(start 0.120396 0.3048)
			(end 0.120396 0.2794)
			(stroke
				(width 0.1)
				(type default)
			)
			(layer "F.Fab")
		)
		(fp_line
			(start 0.120396 0.2794)
			(end -0.12065 0.2794)
			(stroke
				(width 0.1)
				(type default)
			)
			(layer "F.Fab")
		)
		(fp_line
			(start -0.12065 0.3048)
			(end -0.67945 0.3048)
			(stroke
				(width 0.1)
				(type default)
			)
			(layer "F.Fab")
		)
		(fp_line
			(start -0.12065 0.2794)
			(end -0.12065 0.3048)
			(stroke
				(width 0.1)
				(type default)
			)
			(layer "F.Fab")
		)
		(fp_line
			(start -0.12065 -0.2794)
			(end 0.12065 -0.2794)
			(stroke
				(width 0.1)
				(type default)
			)
			(layer "F.Fab")
		)
		(fp_line
			(start -0.12065 -0.305054)
			(end -0.12065 -0.2794)
			(stroke
				(width 0.1)
				(type default)
			)
			(layer "F.Fab")
		)
		(fp_line
			(start -0.67945 0.3048)
			(end -0.67945 -0.305054)
			(stroke
				(width 0.1)
				(type default)
			)
			(layer "F.Fab")
		)
		(fp_line
			(start -0.67945 -0.305054)
			(end -0.12065 -0.305054)
			(stroke
				(width 0.1)
				(type default)
			)
			(layer "F.Fab")
		)
		(pad "1" smd circle
			(at -0.40005 0 180)
			(size 0 0)
			(layers "F.Cu" "F.Mask" "F.Paste")
			(net "SMB_IOEXP_3V3AUX_SDA_R")
		)
		(pad "2" smd circle
			(at 0.40005 0 180)
			(size 0 0)
			(layers "F.Cu" "F.Mask" "F.Paste")
			(net "SMB_IOEXP_3V3AUX_SDA")
		)
	)
	(footprint ""
		(layer "F.Cu")
		(at 136.840976 -380.385828)
		(property "Reference" "C48"
			(at 0 0 0)
			(layer "F.SilkS")
			(hide yes)
			(effects
				(font
					(size 1.27 1.27)
				)
			)
		)
		(property "Value" ""
			(at 0 0 0)
			(layer "F.Fab")
			(effects
				(font
					(size 1.27 1.27)
				)
			)
		)
		(duplicate_pad_numbers_are_jumpers no)
		(fp_line
			(start -0.299974 -0.150114)
			(end 0.299974 -0.150114)
			(stroke
				(width 0.1)
				(type default)
			)
			(layer "F.Fab")
		)
		(fp_line
			(start -0.299974 0.150114)
			(end -0.299974 -0.150114)
			(stroke
				(width 0.1)
				(type default)
			)
			(layer "F.Fab")
		)
		(fp_line
			(start 0.299974 -0.150114)
			(end 0.299974 0.150114)
			(stroke
				(width 0.1)
				(type default)
			)
			(layer "F.Fab")
		)
		(fp_line
			(start 0.299974 0.150114)
			(end -0.299974 0.150114)
			(stroke
				(width 0.1)
				(type default)
			)
			(layer "F.Fab")
		)
		(pad "1" smd rect
			(at -0.2667 0)
			(size 0.3048 0.381)
			(layers "F.Cu" "F.Mask" "F.Paste")
			(net "P5E_CPU1_P3_TX_C_DN<15>")
		)
		(pad "2" smd rect
			(at 0.2667 0)
			(size 0.3048 0.381)
			(layers "F.Cu" "F.Mask" "F.Paste")
			(net "P5E_CPU1_P3_TX_DN<15>")
		)
	)
	(footprint ""
		(layer "F.Cu")
		(at 18.702782 -132.489702)
		(property "Reference" "R3335"
			(at 0 0 0)
			(layer "F.SilkS")
			(hide yes)
			(effects
				(font
					(size 1.27 1.27)
				)
			)
		)
		(property "Value" ""
			(at 0 0 0)
			(layer "F.Fab")
			(effects
				(font
					(size 1.27 1.27)
				)
			)
		)
		(duplicate_pad_numbers_are_jumpers no)
		(fp_line
			(start -0.7874 -0.4064)
			(end 0.7874 -0.4064)
			(stroke
				(width 0.1524)
				(type default)
			)
			(layer "F.SilkS")
		)
		(fp_line
			(start -0.7874 0.4064)
			(end -0.7874 -0.4064)
			(stroke
				(width 0.1524)
				(type default)
			)
			(layer "F.SilkS")
		)
		(fp_line
			(start 0.7874 -0.4064)
			(end 0.7874 0.4064)
			(stroke
				(width 0.1524)
				(type default)
			)
			(layer "F.SilkS")
		)
		(fp_line
			(start 0.7874 0.4064)
			(end -0.7874 0.4064)
			(stroke
				(width 0.1524)
				(type default)
			)
			(layer "F.SilkS")
		)
		(fp_line
			(start -0.67945 -0.305054)
			(end -0.12065 -0.305054)
			(stroke
				(width 0.1)
				(type default)
			)
			(layer "F.Fab")
		)
		(fp_line
			(start -0.67945 0.3048)
			(end -0.67945 -0.305054)
			(stroke
				(width 0.1)
				(type default)
			)
			(layer "F.Fab")
		)
		(fp_line
			(start -0.12065 -0.305054)
			(end -0.12065 -0.2794)
			(stroke
				(width 0.1)
				(type default)
			)
			(layer "F.Fab")
		)
		(fp_line
			(start -0.12065 -0.2794)
			(end 0.12065 -0.2794)
			(stroke
				(width 0.1)
				(type default)
			)
			(layer "F.Fab")
		)
		(fp_line
			(start -0.12065 0.2794)
			(end -0.12065 0.3048)
			(stroke
				(width 0.1)
				(type default)
			)
			(layer "F.Fab")
		)
		(fp_line
			(start -0.12065 0.3048)
			(end -0.67945 0.3048)
			(stroke
				(width 0.1)
				(type default)
			)
			(layer "F.Fab")
		)
		(fp_line
			(start 0.120396 0.2794)
			(end -0.12065 0.2794)
			(stroke
				(width 0.1)
				(type default)
			)
			(layer "F.Fab")
		)
		(fp_line
			(start 0.120396 0.3048)
			(end 0.120396 0.2794)
			(stroke
				(width 0.1)
				(type default)
			)
			(layer "F.Fab")
		)
		(fp_line
			(start 0.12065 -0.3048)
			(end 0.67945 -0.3048)
			(stroke
				(width 0.1)
				(type default)
			)
			(layer "F.Fab")
		)
		(fp_line
			(start 0.12065 -0.2794)
			(end 0.12065 -0.3048)
			(stroke
				(width 0.1)
				(type default)
			)
			(layer "F.Fab")
		)
		(fp_line
			(start 0.67945 -0.3048)
			(end 0.67945 0.3048)
			(stroke
				(width 0.1)
				(type default)
			)
			(layer "F.Fab")
		)
		(fp_line
			(start 0.67945 0.3048)
			(end 0.120396 0.3048)
			(stroke
				(width 0.1)
				(type default)
			)
			(layer "F.Fab")
		)
		(pad "1" smd circle
			(at -0.40005 0)
			(size 0 0)
			(layers "F.Cu" "F.Mask" "F.Paste")
			(net "CLK_100M_BMC_RC_DP_R")
		)
		(pad "2" smd circle
			(at 0.40005 0)
			(size 0 0)
			(layers "F.Cu" "F.Mask" "F.Paste")
			(net "CLK_100M_BMC_RC_DP")
		)
	)
	(footprint ""
		(layer "F.Cu")
		(at 200.952608 -110.577376 180)
		(property "Reference" "R3478"
			(at 0 0 180)
			(layer "F.SilkS")
			(hide yes)
			(effects
				(font
					(size 1.27 1.27)
				)
			)
		)
		(property "Value" ""
			(at 0 0 180)
			(layer "F.Fab")
			(effects
				(font
					(size 1.27 1.27)
				)
			)
		)
		(duplicate_pad_numbers_are_jumpers no)
		(fp_line
			(start 0.7874 0.4064)
			(end -0.7874 0.4064)
			(stroke
				(width 0.1524)
				(type default)
			)
			(layer "F.SilkS")
		)
		(fp_line
			(start 0.7874 -0.4064)
			(end 0.7874 0.4064)
			(stroke
				(width 0.1524)
				(type default)
			)
			(layer "F.SilkS")
		)
		(fp_line
			(start -0.7874 0.4064)
			(end -0.7874 -0.4064)
			(stroke
				(width 0.1524)
				(type default)
			)
			(layer "F.SilkS")
		)
		(fp_line
			(start -0.7874 -0.4064)
			(end 0.7874 -0.4064)
			(stroke
				(width 0.1524)
				(type default)
			)
			(layer "F.SilkS")
		)
		(fp_line
			(start 0.67945 0.3048)
			(end 0.120396 0.3048)
			(stroke
				(width 0.1)
				(type default)
			)
			(layer "F.Fab")
		)
		(fp_line
			(start 0.67945 -0.3048)
			(end 0.67945 0.3048)
			(stroke
				(width 0.1)
				(type default)
			)
			(layer "F.Fab")
		)
		(fp_line
			(start 0.12065 -0.2794)
			(end 0.12065 -0.3048)
			(stroke
				(width 0.1)
				(type default)
			)
			(layer "F.Fab")
		)
		(fp_line
			(start 0.12065 -0.3048)
			(end 0.67945 -0.3048)
			(stroke
				(width 0.1)
				(type default)
			)
			(layer "F.Fab")
		)
		(fp_line
			(start 0.120396 0.3048)
			(end 0.120396 0.2794)
			(stroke
				(width 0.1)
				(type default)
			)
			(layer "F.Fab")
		)
		(fp_line
			(start 0.120396 0.2794)
			(end -0.12065 0.2794)
			(stroke
				(width 0.1)
				(type default)
			)
			(layer "F.Fab")
		)
		(fp_line
			(start -0.12065 0.3048)
			(end -0.67945 0.3048)
			(stroke
				(width 0.1)
				(type default)
			)
			(layer "F.Fab")
		)
		(fp_line
			(start -0.12065 0.2794)
			(end -0.12065 0.3048)
			(stroke
				(width 0.1)
				(type default)
			)
			(layer "F.Fab")
		)
		(fp_line
			(start -0.12065 -0.2794)
			(end 0.12065 -0.2794)
			(stroke
				(width 0.1)
				(type default)
			)
			(layer "F.Fab")
		)
		(fp_line
			(start -0.12065 -0.305054)
			(end -0.12065 -0.2794)
			(stroke
				(width 0.1)
				(type default)
			)
			(layer "F.Fab")
		)
		(fp_line
			(start -0.67945 0.3048)
			(end -0.67945 -0.305054)
			(stroke
				(width 0.1)
				(type default)
			)
			(layer "F.Fab")
		)
		(fp_line
			(start -0.67945 -0.305054)
			(end -0.12065 -0.305054)
			(stroke
				(width 0.1)
				(type default)
			)
			(layer "F.Fab")
		)
		(pad "1" smd circle
			(at -0.40005 0 180)
			(size 0 0)
			(layers "F.Cu" "F.Mask" "F.Paste")
			(net "GPU_FPGA_EROT_RST_N")
		)
		(pad "2" smd circle
			(at 0.40005 0 180)
			(size 0 0)
			(layers "F.Cu" "F.Mask" "F.Paste")
			(net "GPU_FPGA_EROT_RST_R_N")
		)
	)
	(footprint ""
		(layer "F.Cu")
		(at 240.298224 -159.680148)
		(property "Reference" "R6110"
			(at 0 0 0)
			(layer "F.SilkS")
			(hide yes)
			(effects
				(font
					(size 1.27 1.27)
				)
			)
		)
		(property "Value" ""
			(at 0 0 0)
			(layer "F.Fab")
			(effects
				(font
					(size 1.27 1.27)
				)
			)
		)
		(duplicate_pad_numbers_are_jumpers no)
		(fp_line
			(start -0.7874 -0.4064)
			(end 0.7874 -0.4064)
			(stroke
				(width 0.1524)
				(type default)
			)
			(layer "F.SilkS")
		)
		(fp_line
			(start -0.7874 0.4064)
			(end -0.7874 -0.4064)
			(stroke
				(width 0.1524)
				(type default)
			)
			(layer "F.SilkS")
		)
		(fp_line
			(start 0.7874 -0.4064)
			(end 0.7874 0.4064)
			(stroke
				(width 0.1524)
				(type default)
			)
			(layer "F.SilkS")
		)
		(fp_line
			(start 0.7874 0.4064)
			(end -0.7874 0.4064)
			(stroke
				(width 0.1524)
				(type default)
			)
			(layer "F.SilkS")
		)
		(fp_line
			(start -0.67945 -0.305054)
			(end -0.12065 -0.305054)
			(stroke
				(width 0.1)
				(type default)
			)
			(layer "F.Fab")
		)
		(fp_line
			(start -0.67945 0.3048)
			(end -0.67945 -0.305054)
			(stroke
				(width 0.1)
				(type default)
			)
			(layer "F.Fab")
		)
		(fp_line
			(start -0.12065 -0.305054)
			(end -0.12065 -0.2794)
			(stroke
				(width 0.1)
				(type default)
			)
			(layer "F.Fab")
		)
		(fp_line
			(start -0.12065 -0.2794)
			(end 0.12065 -0.2794)
			(stroke
				(width 0.1)
				(type default)
			)
			(layer "F.Fab")
		)
		(fp_line
			(start -0.12065 0.2794)
			(end -0.12065 0.3048)
			(stroke
				(width 0.1)
				(type default)
			)
			(layer "F.Fab")
		)
		(fp_line
			(start -0.12065 0.3048)
			(end -0.67945 0.3048)
			(stroke
				(width 0.1)
				(type default)
			)
			(layer "F.Fab")
		)
		(fp_line
			(start 0.120396 0.2794)
			(end -0.12065 0.2794)
			(stroke
				(width 0.1)
				(type default)
			)
			(layer "F.Fab")
		)
		(fp_line
			(start 0.120396 0.3048)
			(end 0.120396 0.2794)
			(stroke
				(width 0.1)
				(type default)
			)
			(layer "F.Fab")
		)
		(fp_line
			(start 0.12065 -0.3048)
			(end 0.67945 -0.3048)
			(stroke
				(width 0.1)
				(type default)
			)
			(layer "F.Fab")
		)
		(fp_line
			(start 0.12065 -0.2794)
			(end 0.12065 -0.3048)
			(stroke
				(width 0.1)
				(type default)
			)
			(layer "F.Fab")
		)
		(fp_line
			(start 0.67945 -0.3048)
			(end 0.67945 0.3048)
			(stroke
				(width 0.1)
				(type default)
			)
			(layer "F.Fab")
		)
		(fp_line
			(start 0.67945 0.3048)
			(end 0.120396 0.3048)
			(stroke
				(width 0.1)
				(type default)
			)
			(layer "F.Fab")
		)
		(pad "1" smd circle
			(at -0.40005 0)
			(size 0 0)
			(layers "F.Cu" "F.Mask" "F.Paste")
			(net "JTAG_CPUX_TDO_R")
		)
		(pad "2" smd circle
			(at 0.40005 0)
			(size 0 0)
			(layers "F.Cu" "F.Mask" "F.Paste")
			(net "JTAG_CPUX_TDO")
		)
	)
	(footprint ""
		(layer "F.Cu")
		(at 149.478746 -408.517344 -90)
		(property "Reference" "C6715"
			(at 0 0 270)
			(layer "F.SilkS")
			(hide yes)
			(effects
				(font
					(size 1.27 1.27)
				)
			)
		)
		(property "Value" ""
			(at 0 0 270)
			(layer "F.Fab")
			(effects
				(font
					(size 1.27 1.27)
				)
			)
		)
		(duplicate_pad_numbers_are_jumpers no)
		(fp_line
			(start -0.299974 0.150114)
			(end -0.299974 -0.150114)
			(stroke
				(width 0.1)
				(type default)
			)
			(layer "F.Fab")
		)
		(fp_line
			(start 0.299974 0.150114)
			(end -0.299974 0.150114)
			(stroke
				(width 0.1)
				(type default)
			)
			(layer "F.Fab")
		)
		(fp_line
			(start -0.299974 -0.150114)
			(end 0.299974 -0.150114)
			(stroke
				(width 0.1)
				(type default)
			)
			(layer "F.Fab")
		)
		(fp_line
			(start 0.299974 -0.150114)
			(end 0.299974 0.150114)
			(stroke
				(width 0.1)
				(type default)
			)
			(layer "F.Fab")
		)
		(pad "1" smd rect
			(at -0.2667 0 270)
			(size 0.3048 0.381)
			(layers "F.Cu" "F.Mask" "F.Paste")
			(net "P5E_CPU1_P2_TX_BUF_C_DP<11>")
		)
		(pad "2" smd rect
			(at 0.2667 0 270)
			(size 0.3048 0.381)
			(layers "F.Cu" "F.Mask" "F.Paste")
			(net "P5E_CPU1_P2_TX_BUF_DP<11>")
		)
	)
)
